# T6G (Grand Teton) — schematic netlist excerpt (pin names and nets, part order shuffled) for the footprints in the layout excerpt that follows; sources: Cadence DE-HDL packaged netlist, KiCad conversion of 04192023_DAF0TMB3IC0_F0TG_MB_C_brd_V02_OCP.brd

PC6805  Q_CAPP  390UF 2.5V 20% ALUM  pkg SMLF  page 360 : A = P1V8_CPU0_RT_1D ; B = GND
PR272  Q_RES  5.6 1% CHIP  pkg 0402LF  page 220 : A = SW_PVDDCR_CPU1_P1_BOOT5 ; B = SW_PVDDCR_CPU1_P1_BOOT5_R

(kicad_pcb
	(version 20260206)
	(generator "pcbnew")
	(generator_version "10.0")
	(general
		(thickness 1.6)
		(legacy_teardrops no)
	)
	(paper "A4")
	(title_block
		(title "04192023_DAF0TMB3IC0_F0TG_MB_C_brd_V02_OCP.brd")
		(comment 1 "Grand Teton / footprints 3254-3255 of 8354")
	)
	(layers
		(0 "F.Cu" signal "TOP")
		(4 "In1.Cu" signal "GND")
		(6 "In2.Cu" signal "IN1")
		(8 "In3.Cu" signal "GND1")
		(10 "In4.Cu" signal "IN2")
		(12 "In5.Cu" signal "GND2")
		(14 "In6.Cu" signal "IN3")
		(16 "In7.Cu" signal "GND3")
		(18 "In8.Cu" signal "VCC")
		(20 "In9.Cu" signal "VCC1")
		(22 "In10.Cu" signal "GND4")
		(24 "In11.Cu" signal "IN4")
		(26 "In12.Cu" signal "GND5")
		(28 "In13.Cu" signal "IN5")
		(30 "In14.Cu" signal "GND6")
		(32 "In15.Cu" signal "IN6")
		(34 "In16.Cu" signal "GND7")
		(2 "B.Cu" signal "BOTTOM")
		(9 "F.Adhes" user "F.Adhesive")
		(11 "B.Adhes" user "B.Adhesive")
		(13 "F.Paste" user "Package Geometry/Pastemask Top")
		(15 "B.Paste" user "Package Geometry/Pastemask Bottom")
		(5 "F.SilkS" user "Ref Des/Silkscreen Top")
		(7 "B.SilkS" user "Ref Des/Silkscreen Bottom")
		(1 "F.Mask" user "Board Geometry/Soldermask Top")
		(3 "B.Mask" user "Board Geometry/Soldermask Bottom")
		(17 "Dwgs.User" user "User.Drawings")
		(19 "Cmts.User" user "User.Comments")
		(21 "Eco1.User" user "User.Eco1")
		(23 "Eco2.User" user "User.Eco2")
		(25 "Edge.Cuts" user "Board Geometry/Outline")
		(27 "Margin" user)
		(31 "F.CrtYd" user "Package Geometry/Place Bound Top")
		(29 "B.CrtYd" user "Package Geometry/Place Bound Bottom")
		(35 "F.Fab" user "Ref Des/Assembly Top")
		(33 "B.Fab" user "Ref Des/Assembly Bottom")
	)
	(footprint ""
		(layer "F.Cu")
		(at 96.21266 -339.681058 90)
		(property "Reference" "PR272"
			(at 0 0 90)
			(layer "F.SilkS")
			(hide yes)
			(effects
				(font
					(size 1.27 1.27)
				)
			)
		)
		(property "Value" ""
			(at 0 0 90)
			(layer "F.Fab")
			(effects
				(font
					(size 1.27 1.27)
				)
			)
		)
		(duplicate_pad_numbers_are_jumpers no)
		(fp_line
			(start 0.7874 -0.4064)
			(end 0.7874 0.4064)
			(stroke
				(width 0.1524)
				(type default)
			)
			(layer "F.SilkS")
		)
		(fp_line
			(start -0.7874 -0.4064)
			(end 0.7874 -0.4064)
			(stroke
				(width 0.1524)
				(type default)
			)
			(layer "F.SilkS")
		)
		(fp_line
			(start 0.7874 0.4064)
			(end -0.7874 0.4064)
			(stroke
				(width 0.1524)
				(type default)
			)
			(layer "F.SilkS")
		)
		(fp_line
			(start -0.7874 0.4064)
			(end -0.7874 -0.4064)
			(stroke
				(width 0.1524)
				(type default)
			)
			(layer "F.SilkS")
		)
		(fp_line
			(start -0.12065 -0.305054)
			(end -0.12065 -0.2794)
			(stroke
				(width 0.1)
				(type default)
			)
			(layer "F.Fab")
		)
		(fp_line
			(start -0.67945 -0.305054)
			(end -0.12065 -0.305054)
			(stroke
				(width 0.1)
				(type default)
			)
			(layer "F.Fab")
		)
		(fp_line
			(start 0.67945 -0.3048)
			(end 0.67945 0.3048)
			(stroke
				(width 0.1)
				(type default)
			)
			(layer "F.Fab")
		)
		(fp_line
			(start 0.12065 -0.3048)
			(end 0.67945 -0.3048)
			(stroke
				(width 0.1)
				(type default)
			)
			(layer "F.Fab")
		)
		(fp_line
			(start 0.12065 -0.2794)
			(end 0.12065 -0.3048)
			(stroke
				(width 0.1)
				(type default)
			)
			(layer "F.Fab")
		)
		(fp_line
			(start -0.12065 -0.2794)
			(end 0.12065 -0.2794)
			(stroke
				(width 0.1)
				(type default)
			)
			(layer "F.Fab")
		)
		(fp_line
			(start 0.120396 0.2794)
			(end -0.12065 0.2794)
			(stroke
				(width 0.1)
				(type default)
			)
			(layer "F.Fab")
		)
		(fp_line
			(start -0.12065 0.2794)
			(end -0.12065 0.3048)
			(stroke
				(width 0.1)
				(type default)
			)
			(layer "F.Fab")
		)
		(fp_line
			(start 0.67945 0.3048)
			(end 0.120396 0.3048)
			(stroke
				(width 0.1)
				(type default)
			)
			(layer "F.Fab")
		)
		(fp_line
			(start 0.120396 0.3048)
			(end 0.120396 0.2794)
			(stroke
				(width 0.1)
				(type default)
			)
			(layer "F.Fab")
		)
		(fp_line
			(start -0.12065 0.3048)
			(end -0.67945 0.3048)
			(stroke
				(width 0.1)
				(type default)
			)
			(layer "F.Fab")
		)
		(fp_line
			(start -0.67945 0.3048)
			(end -0.67945 -0.305054)
			(stroke
				(width 0.1)
				(type default)
			)
			(layer "F.Fab")
		)
		(pad "1" smd circle
			(at -0.40005 0 90)
			(size 0 0)
			(layers "F.Cu" "F.Mask" "F.Paste")
			(net "SW_PVDDCR_CPU1_P1_BOOT5")
		)
		(pad "2" smd circle
			(at 0.40005 0 90)
			(size 0 0)
			(layers "F.Cu" "F.Mask" "F.Paste")
			(net "SW_PVDDCR_CPU1_P1_BOOT5_R")
		)
	)
	(footprint ""
		(layer "F.Cu")
		(at 247.499378 -315.82868 90)
		(property "Reference" "PC6805"
			(at -1.75768 5.257292 90)
			(unlocked yes)
			(layer "F.SilkS")
			(effects
				(font
					(size 0.7874 0.5842)
					(thickness 0.1524)
				)
				(justify left)
			)
		)
		(property "Value" ""
			(at 0 0 90)
			(layer "F.Fab")
			(effects
				(font
					(size 1.27 1.27)
				)
			)
		)
		(duplicate_pad_numbers_are_jumpers no)
		(fp_line
			(start 2.750058 -2.750058)
			(end -1.988058 -2.750058)
			(stroke
				(width 0.1524)
				(type default)
			)
			(layer "F.SilkS")
		)
		(fp_line
			(start -1.988058 -2.750058)
			(end -2.750058 -1.988058)
			(stroke
				(width 0.1524)
				(type default)
			)
			(layer "F.SilkS")
		)
		(fp_line
			(start -2.750058 -1.988058)
			(end -2.750058 -0.9398)
			(stroke
				(width 0.1524)
				(type default)
			)
			(layer "F.SilkS")
		)
		(fp_line
			(start 2.750058 -0.9398)
			(end 2.750058 -2.750058)
			(stroke
				(width 0.1524)
				(type default)
			)
			(layer "F.SilkS")
		)
		(fp_line
			(start -2.750058 0.9398)
			(end -2.750058 1.988058)
			(stroke
				(width 0.1524)
				(type default)
			)
			(layer "F.SilkS")
		)
		(fp_line
			(start -2.750058 1.988058)
			(end -1.988058 2.750058)
			(stroke
				(width 0.1524)
				(type default)
			)
			(layer "F.SilkS")
		)
		(fp_line
			(start 2.750058 2.750058)
			(end 2.750058 0.9398)
			(stroke
				(width 0.1524)
				(type default)
			)
			(layer "F.SilkS")
		)
		(fp_line
			(start -1.988058 2.750058)
			(end 2.750058 2.750058)
			(stroke
				(width 0.1524)
				(type default)
			)
			(layer "F.SilkS")
		)
		(fp_line
			(start 2.750058 -2.750058)
			(end -2.750058 -2.750058)
			(stroke
				(width 0.1)
				(type default)
			)
			(layer "F.Fab")
		)
		(fp_line
			(start -2.750058 -2.750058)
			(end -2.750058 2.750058)
			(stroke
				(width 0.1)
				(type default)
			)
			(layer "F.Fab")
		)
		(fp_line
			(start 2.750058 2.750058)
			(end 2.750058 -2.750058)
			(stroke
				(width 0.1)
				(type default)
			)
			(layer "F.Fab")
		)
		(fp_line
			(start -2.750058 2.750058)
			(end 2.750058 2.750058)
			(stroke
				(width 0.1)
				(type default)
			)
			(layer "F.Fab")
		)
		(pad "1" smd rect
			(at -2.199894 0 180)
			(size 1.6002 3.0226)
			(layers "F.Cu" "F.Mask" "F.Paste")
			(net "P1V8_CPU0_RT_1D")
		)
		(pad "2" smd rect
			(at 2.199894 0 180)
			(size 1.6002 3.0226)
			(layers "F.Cu" "F.Mask" "F.Paste")
			(net "GND")
		)
	)
)
